# BASEBOARD_FAB2 (Tioga Pass) — schematic parts with pin connectivity, parts 3617–3778 of 4751; source: Cadence DE-HDL packaged netlist (pstxprt.dat, pstxnet.dat, pstchip.dat)

R7C4  RES  0.0 5% CHIP  pkg 0402  page 114 : 1 = CLK_100M_BMC_PE_R_DP ; 2 = CLK_100M_BMC_PE_DP
R7C5  RES  10.0K 1% CHIP  pkg 0402  page 133 : 1 = P3V3_STBY ; 2 = FM_SINT_PRSNT_N
R7C6  RES  10M 1.0% CHIP  pkg 0603  page 114 : 1 = XTAL_33K_RTC1 ; 2 = XTAL_33K_RTC2
R7C8  RES  10.0K 1% CHIP  pkg 0402  page 133 : 1 = P3V3_STBY ; 2 = FM_WBG_PRSNT_N
R7C10  RES  20.0K 1% CHIP  pkg 0402  page 137 : 1 = P3V3_RTC_STBY ; 2 = RST_RTCRST_N
R7C11  RES  1.0M 1% EMPTY  pkg 0402  page 137 : 1 = GND ; 2 = RST_RTCRST_N
R7C13  RES  10.0K 1% CHIP  pkg 0402  page 137 : 1 = P3V3_STBY ; 2 = FM_UART_PRES_N
R7C14  RES  33.2 1% CHIP  pkg 0402  page 121 : 1 = RMII_BMC_PCH_SPRNGVLLE_RXER ; 2 = RMII_BMC_PCH_SPRNGVLLE_RXER_R
R7C15  RES  0.0 5% CHIP  pkg 0402  page 121 : 1 = SPI_PCH_MOSI_R ; 2 = SPI_PCH_MOSI
R7C16  RES  33.2 1% CHIP  pkg 0402  page 121 : 1 = SPI_PCH_CS0_R_N ; 2 = SPI_PCH_CS0_N
R7C17  RES  4.75K 1% CHIP  pkg 0402  page 166 : 1 = PVCCIO_CPU0 ; 2 = PECI_BMC
R7C20  RES  10.0K 1% CHIP  pkg 0402  page 121 : 1 = CLK_50M_CKMNG_PCH_10GBE ; 2 = GND
R7C21  RES  10.0K 1% CHIP  pkg 0402  page 134 : 1 = P1V05_PCH_STBY ; 2 = FM_PCH_LVC1_THERMTRIP_N
R7C23  RES  10.0K 1% CHIP  pkg 0402  page 118 : 1 = P3V3_STBY ; 2 = XDP_PCH_PWR_DEBUG_N
R7C24  RES  4.02K 1% CHIP  pkg 0402  page 194 : 1 = VR_PVCCMCP_CPU0_XADDR2 ; 2 = GND
R7C25  RES  68.1K 1% EMPTY  pkg 0402  page 212 : 1 = VR_PVCCIO_CPU0_OCSET ; 2 = GND
R7C26  RES  33.2 1% CHIP  pkg 0402  page 119 : 1 = CLK_24M_BMC_LPC ; 2 = CLK_24M_BMC_LPC_R
R7D1  RES  1.00K 1% EMPTY  pkg 0402  page 125 : 1 = RMII_PCH_SPRNGVLLE_ARB_OUT ; 2 = GND
R7D2  RES  1.00K 1% CHIP  pkg 0402  page 133 : 1 = P3V3_STBY ; 2 = PU_FM_RCIN_N
R7D3  RES  4.75K 1% CHIP  pkg 0402  page 133 : 1 = P3V3_STBY ; 2 = IRQ_LPC_SERIRQ_N
R7D4  RES  10.0K 1% CHIP  pkg 0402  page 133 : 1 = P3V3_STBY ; 2 = PU_IRQ_PCH_SCI_WHEA_N
R7D5  RES  2.26K 1.0% CHIP  pkg 0402  page 181 : 1 = P3V3_STBY ; 2 = FM_MB_SLOT_ID0
R7D6  RES  4.75K 1% CHIP  pkg 0402  page 133 : 1 = P3V3_STBY ; 2 = FM_BMC_READY_N
R7D7  RES  1.00K 1% CHIP  pkg 0402  page 133 : 1 = P3V3_STBY ; 2 = IRQ_PIRQA_SPI_TPM_N
R7D8  RES  10.0K 1% CHIP  pkg 0402  page 133 : 1 = P3V3_STBY ; 2 = PU_LPC_CLKRUN_N
R7D9  RES  2.26K 1.0% CHIP  pkg 0402  page 181 : 1 = P3V3_STBY ; 2 = FM_MB_SLOT_ID1
R7D10  RES  10.0K 1% CHIP  pkg 0402  page 133 : 1 = P3V3_STBY ; 2 = PU_LPC_PME_N
R7D12  RES  10.0K 1% CHIP  pkg 0402  page 133 : 1 = P3V3_STBY ; 2 = FM_OCP_MEZZA_PRES
R7D13  RES  8.2K 1% EMPTY  pkg 0402  page 125 : 1 = P3V3_STBY ; 2 = RMII_BMC_PCH_SPRNGVLLE_RXER
R7D15  RES  348 1% CHIP  pkg 0402  page 166 : 1 = PECI_PCH ; 2 = GND
R7D18  RES  1.00K 1% CHIP  pkg 0402  page 134 : 1 = FM_THERMTRIP_DLY ; 2 = FM_THERMTRIP_DLY_R
R7D19  RES  1.00K 1% EMPTY  pkg 0402  page 126 : 1 = FM_OC_DETECT_EN_N ; 2 = GND
R7D23  RES  0.0 5% CHIP  pkg 0402  page 118 : 1 = RST_BMC_SRST_N ; 2 = RST_BMC_SRST_R_N
R7D24  RES  33.2 1% CHIP  pkg 0402  page 93 : 1 = FM_CPU1_PROCHOT_LVT3_K_N ; 2 = FM_CPU1_PROCHOT_LVT3_N
R7D25  RES  33.2 1% CHIP  pkg 0402  page 92 : 1 = FM_CPU_MSMI_LVT3_R_N ; 2 = FM_CPU_MSMI_LVT3_N
R7D26  RES  1.00K 1% CHIP  pkg 0402  page 92 : 1 = PD_GTL2104_DIR_0 ; 2 = GND
R7D27  RES  0.0 5% CHIP  pkg 0402  page 92 : 1 = H_CPU0_MSMI_G_N ; 2 = H_CPU_MSMI_G_N
R7D28  RES  0.0 5% CHIP  pkg 0402  page 92 : 1 = H_CPU1_MSMI_G_N ; 2 = H_CPU_MSMI_G_N
R7D29  RES  33.2 1% CHIP  pkg 0402  page 92 : 1 = FM_CPU0_FIVR_FAULT_R_LVT3 ; 2 = FM_CPU0_FIVR_FAULT_LVT3
R7D30  RES  4.75K 1% CHIP  pkg 0402  page 135 : 1 = P3V3_STBY ; 2 = FM_CPLD_UART_CH_LOCK_N
R7D31  RES  33.2 1% CHIP  pkg 0402  page 92 : 1 = FM_CPU_ERR2_LVT3_R_N ; 2 = FM_CPU_ERR2_LVT3_N
R7D32  RES  100.0 1% CHIP  pkg 0402  page 92 : 1 = P0V7_GTL2104_VREF_0 ; 2 = GND
R7D33  374R2F-1-GP  1%  pkg SMD-RG  page 92 : 1 = P3V3 ; 2 = P0V7_GTL2104_VREF_0
R7D34  RES  33.2 1% CHIP  pkg 0402  page 92 : 1 = FM_CPU0_THERMTRIP_LVT3_R_N ; 2 = FM_CPU0_THERMTRIP_LVT3_N
R7D36  RES  0.0 5% CHIP  pkg 0402  page 104 : 1 = FM_156M_CPU1_BRD_OSC_EN ; 2 = FM_CPU1_STL_BRD_OSC_EN
R7D37  RES  0.0 5% CHIP  pkg 0402  page 104 : 1 = FM_CPU1_VRM_OSC_EN ; 2 = FM_CPU1_VRM_322M_156M_OSC_EN
R7D38  RES  0.0 5% EMPTY  pkg 0402  page 104 : 1 = FM_CPU1_VRM_OSC_EN ; 2 = FM_CPU1_STL_BRD_OSC_EN
R7D39  RES  0.0 5% CHIP  pkg 0402  page 104 : 1 = FM_CPU0_VRM_OSC_EN ; 2 = FM_CPU0_VRM_322M_156M_OSC_EN
R7D40  RES  0.0 5% EMPTY  pkg 0402  page 104 : 1 = FM_CPU0_VRM_OSC_EN ; 2 = FM_CPU0_STL_BRD_OSC_EN
R7D41  RES  0.0 5% CHIP  pkg 0402  page 93 : 1 = FM_CPU1_PROCHOT_LVT3_R_N ; 2 = FM_CPU1_PROCHOT_LVT3_K_N
R7D42  RES  4.75K 1% CHIP  pkg 0402  page 191 : 1 = P3V3_STBY ; 2 = PU_FAB2_MARKER_CPLD
R7D43  RES  0.0 5% EMPTY  pkg 0402  page 93 : 1 = FM_CPU1_PROCHOT_LVT3_K_N ; 2 = H_CPU1_PROCHOT_G_PCH_N
R7D44  RES  4.75K 1% CHIP  pkg 0402  page 133 : 1 = P1V05_PCH_STBY ; 2 = FM_OCP_MEZZB_PRES_1V05_PCH_N
R7E2  RES  75 1.0% CHIP  pkg 0402  page 92 : 1 = PVCCIO_CPU0 ; 2 = H_CPU0_THERMTRIP_G_N
R7E5  RES  10.0K 1% CHIP  pkg 0402  page 192 : 1 = P3V3_STBY ; 2 = PU_THERMTRIP_FORCE_N
R7E6  RES  10.0K 1% CHIP  pkg 0402  page 192 : 1 = P3V3_STBY ; 2 = PU_RST_PERST_BIT1
R7E7  RES  4.75K 1% CHIP  pkg 0402  page 95 : 1 = P3V3 ; 2 = FM_SYS_THROTTLE_LVC3
R7E9  RES  0.0 5% CHIP  pkg 0402  page 95 : 1 = FM_THROTTLE_N ; 2 = FM_THROTTLE_R_N
R7E10  RES  4.75K 1% CHIP  pkg 0402  page 95 : 1 = P3V3 ; 2 = IRQ_CPU0_VRHOT
R7E11  RES  4.75K 1% CHIP  pkg 0402  page 95 : 1 = P3V3 ; 2 = IRQ_CPU1_VRHOT
R7E12  RES  1.00K 1% CHIP  pkg 0402  page 241 : 1 = P5V_STBY ; 2 = PWRGD_P5V_STBY_R
R7E13  RES  0.0 5% CHIP  pkg 0402  page 241 : 1 = GND ; 2 = AGND_P5V_STBY
R7E14  RES  75K 1% CHIP  pkg 0402  page 241 : 1 = VR_P5V_STBY_RT ; 2 = AGND_P5V_STBY
R7E15  RES  22.1 1.0% CHIP  pkg 0402  page 241 : 1 = PWRGD_P5V_STBY_R ; 2 = PWRGD_P5V_STBY
R7E16  RES  1.37K 1% CHIP  pkg 0402  page 241 : 1 = VR_P5V_STBY_VSENSE ; 2 = AGND_P5V_STBY
R7E17  RES  0.0 5% CHIP  pkg 0402  page 241 : 1 = VR_FET_SW_P5V_STBY_PVIN ; 2 = VR_P5V_STBY_VIN
R7E18  RES  4.75K 1% CHIP  pkg 0402  page 192 : 1 = P3V3_STBY ; 2 = RST_RSMRST_N
R7E19  RES  1.00K 1% EMPTY  pkg 0402  page 192 : 1 = P3V3_STBY ; 2 = FM_MEM_EVENT_FUNC
R7E20  RES  1.00K 1% CHIP  pkg 0402  page 192 : 1 = FM_MEM_EVENT_FUNC ; 2 = GND
R7E21  RES  4.75K 1% CHIP  pkg 0402  page 108 : 1 = P3V3 ; 2 = FM_PWRBRK_N
R7E22  RES  0.0 5% CHIP  pkg 0402  page 108 : 1 = FM_PWRBRK_N ; 2 = FM_PWRBRK_SLOT_N
R7F1  RES  10.0K 1% CHIP  pkg 0402  page 241 : 1 = VR_P5V_STBY_VSENSE_R ; 2 = VR_P5V_STBY_VSENSE
R7F3  RES  33.2 1% CHIP  pkg 0402  page 153 : 1 = SPI_BIOS_SOCKET_IO3 ; 2 = PU_BIOS_SPI_HOLD0_N
R7F4  RES  33.2 1% CHIP  pkg 0402  page 153 : 1 = SPI_SWITCH_MISO ; 2 = SPI_MISO_R0
R7F5  RES  4.75K 1% CHIP  pkg 0402  page 153 : 1 = P3V3_STBY ; 2 = SPI_CS0_PRIMARY_R_N
R7F6  RES  4.75K 1% EMPTY  pkg 0402  page 153 : 1 = P3V3_STBY ; 2 = PU_SPI0_RST
R7F7  RES  2.2 5% EMPTY  pkg 0402  page 231 : 1 = VR_PVPP_ABC_SNUB ; 2 = GND
R7F8  RES  0 5.0% CHIP  pkg 0603  page 231 : 1 = VR_PVPP_ABC_BOOT ; 2 = VR_PVPP_ABC_BOOT_R
R7F9  RES  0.0 5% CHIP  pkg 0402  page 231 : 1 = FM_PVPP_CPU0_EN ; 2 = FM_PVPP_PVDDQ_CPU0_EN_ABC
R7F10  RES  120.0 1% CHIP  pkg 0603  page 231 : 1 = PVPP_ABC ; 2 = GND
R7F11  RES  6.19K 1% CHIP  pkg 0402  page 231 : 1 = VR_FB_PVPP_ABC ; 2 = AGND_PVPP_ABC
R7F12  RES  0.0 5% CHIP  pkg 0402  page 231 : 1 = PVPP_ABC ; 2 = VSENSE_PVPP_ABC
R7F13  RES  20.0K 1% CHIP  pkg 0402  page 231 : 1 = VSENSE_PVPP_ABC ; 2 = VR_FB_PVPP_ABC
R7F14  RES  10.0K 1% CHIP  pkg 0402  page 231 : 1 = FM_PVPP_CPU0_EN ; 2 = GND
R7F15  RES  7.87K 1.0% CHIP  pkg 0402  page 231 : 1 = VR_PVPP_ABC_ISET ; 2 = AGND_PVPP_ABC
R7F16  RES  22.1 1.0% CHIP  pkg 0402  page 231 : 1 = PWRGD_PVPP_ABC_R ; 2 = PWRGD_PVPP_ABC
R7F17  RES  1.0K 0.1% CHIP  pkg 0402  page 231 : 1 = VSENSE_PVPP_ABC ; 2 = VR_COMP_PVPP_ABC
R7F18  RES  7.87K 1.0% CHIP  pkg 0402  page 231 : 1 = VR_COMP_RC_PVPP_ABC ; 2 = VR_FB_PVPP_ABC
R7F19  RES  1.00K 1% CHIP  pkg 0402  page 231 : 1 = P3V3_STBY ; 2 = PWRGD_PVPP_ABC_R
R7F20  RES  100.0K 1% EMPTY  pkg 0402  page 215 : 1 = P3V3_STBY ; 2 = VR_PVDDQ_ABC_VREN
R7F21  RES  0.0 5% CHIP  pkg 0402  page 215 : 1 = FM_PVDDQ_ABC_EN ; 2 = VR_PVDDQ_ABC_VREN
R7F22  RES  1.00K 1% CHIP  pkg 0402  page 215 : 1 = P3V3_STBY ; 2 = PWRGD_PVDDQ_ABC_R
R7F23  RES  33.2 1% CHIP  pkg 0402  page 215 : 1 = IRQ_PVDDQ_ABC_VRHOT_LVT3_R_N ; 2 = IRQ_PVDDQ_ABC_VRHOT_LVT3_N
R7F24  RES  22.1 1.0% CHIP  pkg 0402  page 215 : 1 = PWRGD_PVDDQ_ABC_R ; 2 = PWRGD_PVDDQ_ABC
R7F27  RES  1.00K 1% CHIP  pkg 0402  page 215 : 1 = P3V3_STBY ; 2 = IRQ_PVDDQ_ABC_VRHOT_LVT3_R_N
R7F28  RES  10.0K 1% CHIP  pkg 0402  page 153 : 1 = P3V3_STBY ; 2 = PU_BIOS_SPI_WP0_N
R7F29  RES  33.2 1% CHIP  pkg 0402  page 153 : 1 = SPI_SWITCH_MOSI ; 2 = SPI_SWITCH_MOSI_R0
R7F30  RES  10.0K 1% EMPTY  pkg 0402  page 153 : 1 = PU_BIOS_SPI_WP0_N ; 2 = GND
R7F32  RES  10.0K 1% CHIP  pkg 0402  page 153 : 1 = P3V3_STBY ; 2 = PU_BIOS_SPI_HOLD0_N
R7F33  RES  4.75K 1% CHIP  pkg 0402  page 161 : 1 = P5V_STBY ; 2 = FAN_PWM_OUT_SYS1_R
R7F35  RES  0.0 5% CHIP  pkg 0402  page 231 : 1 = GND ; 2 = AGND_PVPP_ABC
R7F36  RES  2.26K 1.0% CHIP  pkg 0402  page 215 : 1 = P3V3_STBY ; 2 = PWRGD_PVDDQ_ABC
R7F37  RES  33.2 1% CHIP  pkg 0402  page 153 : 1 = SPI_BIOS_SOCKET_IO2 ; 2 = PU_BIOS_SPI_WP0_N
R7G2  RES  0.0 5% CHIP  pkg 0402  page 215 : 1 = SVID_VDIO_PVDDQ_ABC ; 2 = SVID_DIO1_CPU0_R
R7G4  RES  0.0 5% CHIP  pkg 0402  page 215 : 1 = SVID_ALERT_PVDDQ_ABC ; 2 = SVID_ALERT1_CPU0_R_N
R7G7  RES  4.75K 1% CHIP  pkg 0402  page 94 : 1 = P3V3 ; 2 = H_CPU0_MEMABC_MEMHOT
R7G8  RES  2.26K 1.0% CHIP  pkg 0402  page 215 : 1 = VR_PVDDQ_ABC_XADDR1 ; 2 = GND
R7G9  RES  10.0 1% CHIP  pkg 0402  page 215 : 1 = VSENSE_PVDDQ_ABC_P ; 2 = VR_PVDDQ_ABC_AVSP
R7G10  RES  2.26K 1.0% CHIP  pkg 0402  page 215 : 1 = VR_PVDDQ_ABC_XADDR2 ; 2 = GND
R7G14  RES  0.0 5% CHIP  pkg 0402  page 189 : 1 = JTAG_PLD_TDO_MUX_R ; 2 = JTAG_PLD_TDO_MUX
R7G15  RES  0.0 5% EMPTY  pkg 0402  page 189 : 1 = JTAG_PCH_PLD_TDO ; 2 = JTAG_TDO
R7G16  RES  0.0 5% EMPTY  pkg 0402  page 189 : 1 = JTAG_PCH_GBE_TDO ; 2 = JTAG_TDO
R7G17  RES  0.0 5% CHIP  pkg 0402  page 189 : 1 = JTAG_BMC_TDO ; 2 = JTAG_TDO
R7G18  RES  0.0 5% EMPTY  pkg 0402  page 189 : 1 = JTAG_PCH_PLD_TDI ; 2 = JTAG_TDI
R7G19  RES  0.0 5% EMPTY  pkg 0402  page 189 : 1 = JTAG_PCH_GBE_TDI ; 2 = JTAG_TDI
R7G21  RES  0.0 5% CHIP  pkg 0402  page 189 : 1 = JTAG_TDO ; 2 = JTAG_TDO_R
R7G22  RES  10.0K 1% CHIP  pkg 0402  page 189 : 1 = P3V3_STBY ; 2 = JTAG_TDO_R
R7G23  RES  10.0K 1% CHIP  pkg 0402  page 189 : 1 = P3V3_STBY ; 2 = JTAG_TDI_R
R7G24  RES  150.0 1% CHIP  pkg 0402  page 215 : 1 = SVID_CLK1_CPU0_R ; 2 = SVID_CLK_PVDDQ_ABC
R7G25  RES  68.1K 1% EMPTY  pkg 0402  page 216 : 1 = VR_PVDDQ_ABC_PH1_OCSET ; 2 = GND
R7G26  RES  10.0K 1% CHIP  pkg 0402  page 136 : 1 = P3V3_STBY ; 2 = FM_ME_RECOVER_N
R7G27  RES  1.00K 1% CHIP  pkg 0402  page 136 : 1 = P3V3_STBY ; 2 = PU_BIOS_USB_RECOVERY
R7G28  RES  1.00K 1% CHIP  pkg 0402  page 136 : 1 = PD_ME_RCVR_N ; 2 = GND
R7G29  RES  1.00K 1% CHIP  pkg 0402  page 136 : 1 = PD_PASSWORD_CLEAR ; 2 = GND
R7G30  RES  68.1K 1% EMPTY  pkg 0402  page 216 : 1 = VR_PVDDQ_ABC_PH2_OCSET ; 2 = GND
R7G31  RES  1.00K 1% CHIP  pkg 0402  page 136 : 1 = P3V3_STBY ; 2 = PU_BIOS_RECOVER_BOOT
R7G114  RES  0.0 5% CHIP  pkg 0402  page 189 : 1 = BMC_JTAG_SEL_N ; 2 = BMC_JTAG_SEL_N_MUX
R7L2  RES  100.0 1% EMPTY  pkg 0402  page 228 : 1 = VSENSE_PVDDQ_KLM_P ; 2 = VSENSE_PVDDQ_KLM_N
R7M1  RES  665 1.0% CHIP  pkg 0402  page 99 : 1 = PVPP_KLM ; 2 = SMB_DDR_KLM_VPP_SCL_R
R7M2  RES  240 1.0% CHIP  pkg 0402  page 99 : 1 = PVCCIO_CPU1 ; 2 = SMB_DDR_KLM_SCL_G
R7M3  RES  10.0 1% CHIP  pkg 0402  page 99 : 1 = SMB_DDR_KLM_SCL_G_R ; 2 = SMB_DDR_KLM_SCL_G
R7M4  RES  20.0 1% CHIP  pkg 0402  page 99 : 1 = SMB_DDR_KLM_VPP_SCL_R ; 2 = SMB_DDR_KLM_VPP_SCL
R7M5  RES  20.0 1% CHIP  pkg 0402  page 99 : 1 = SMB_DDR_KLM_VPP_SDA_R ; 2 = SMB_DDR_KLM_VPP_SDA
R7M6  RES  665 1.0% CHIP  pkg 0402  page 99 : 1 = PVPP_KLM ; 2 = SMB_DDR_KLM_VPP_SDA_R
R7M7  RES  240 1.0% CHIP  pkg 0402  page 99 : 1 = PVCCIO_CPU1 ; 2 = SMB_DDR_KLM_SDA_G
R7M8  RES  10.0 1% CHIP  pkg 0402  page 99 : 1 = SMB_DDR_KLM_SDA_G_R ; 2 = SMB_DDR_KLM_SDA_G
R7M9  RES  64.9 1.0% CHIP  pkg 0402  page 96 : 1 = PVDDQ_KLM ; 2 = PWRGD_CPU1_DRAMPWROK_KLM_G
R7P1  RES  42.2 1.0% EMPTY  pkg 0402  page 103 : 1 = CLK_100M_CPU1_BCLK2_DP ; 2 = GND
R7P2  RES  42.2 1.0% EMPTY  pkg 0402  page 103 : 1 = CLK_100M_CPU1_BCLK2_DN ; 2 = GND
R7P3  RES  42.2 1.0% EMPTY  pkg 0402  page 103 : 1 = CLK_100M_CPU1_PE_REFCLK_DP ; 2 = GND
R7P4  RES  42.2 1.0% EMPTY  pkg 0402  page 103 : 1 = CLK_100M_CPU1_PE_REFCLK_DN ; 2 = GND
R7P5  RES  150.0 1% CHIP  pkg 0402  page 152 : 1 = H_CPU1_MEMGHJ_MEMHOT_G_N ; 2 = PVCCIO_CPU1
R7P6  RES  42.2 1.0% EMPTY  pkg 0402  page 103 : 1 = CLK_100M_CPU1_RC_REFCLK0_DP ; 2 = GND
R7P7  RES  42.2 1.0% EMPTY  pkg 0402  page 103 : 1 = CLK_100M_CPU1_RC_REFCLK0_DN ; 2 = GND
R7P8  RES  49.9 1% CHIP  pkg 0402  page 55 : 1 = A_CPU1_PE3_RBIAS ; 2 = GND
R7P9  RES  42.2 1.0% EMPTY  pkg 0402  page 103 : 1 = CLK_100M_CPU1_RC_REFCLK1_DP ; 2 = GND
R7P10  RES  49.9 1% CHIP  pkg 0402  page 55 : 1 = A_CPU1_PE012_RBIAS ; 2 = GND
R7P11  RES  49.9 1% CHIP  pkg 0402  page 55 : 1 = A_CPU1_UPI2_RBIAS ; 2 = GND
R7P12  RES  42.2 1.0% EMPTY  pkg 0402  page 103 : 1 = CLK_100M_CPU1_RC_REFCLK1_DN ; 2 = GND
R7P13  RES  10.0K 1% CHIP  pkg 0402  page 97 : 1 = GND ; 2 = PD_CPU1_MCP01_DMON
R7P14  RES  240 1.0% CHIP  pkg 0402  page 90 : 1 = GND ; 2 = PD_CPU1_DMIMODE_OVERRIDE
R7P15  RES  240 1.0% EMPTY  pkg 0402  page 90 : 1 = GND ; 2 = PD_CPU1_KSFC_DIS
R7P16  RES  90.9 1% CHIP  pkg 0402  page 55 : 1 = A_CPU1_GHJ_RCOMP0 ; 2 = GND
R7P17  RES  90.9 1% CHIP  pkg 0402  page 55 : 1 = A_CPU1_GHJ_RCOMP1 ; 2 = GND
R7P18  RES  150.0 1% CHIP  pkg 0402  page 92 : 1 = PVCCIO_CPU0 ; 2 = H_CPU1_CATERR_G_N
R7P19  RES  100.0 1% CHIP  pkg 0402  page 55 : 1 = A_CPU1_GHJ_RCOMP2 ; 2 = GND
R7P20  RES  150.0 1% CHIP  pkg 0402  page 97 : 1 = PVCCIO_CPU0 ; 2 = H_CPU1_FAST_WAKE_N
R7P21  RES  150.0 1% CHIP  pkg 0402  page 152 : 1 = H_CPU1_MEMKLM_MEMHOT_G_N ; 2 = PVCCIO_CPU1
R7P22  RES  240 1.0% EMPTY  pkg 0402  page 90 : 1 = PVCCIO_CPU1 ; 2 = PU_CPU1_LEGACY_SKT
R7P25  RES  49.9 1% CHIP  pkg 0402  page 55 : 1 = H_PM_SYNC_GTL_R2 ; 2 = H_PM_SYNC_GTL
R7P26  RES  49.9 1% CHIP  pkg 0402  page 55 : 1 = H_PMSYNC_CLK_24M_CPU1 ; 2 = H_PMSYNC_CLK_24M
R7P27  RES  150.0 1% CHIP  pkg 0402  page 92 : 1 = PVCCIO_CPU0 ; 2 = H_CPU1_MSMI_G_N
